# SCM (Grand Teton) — schematic netlist excerpt (pin names and nets, part order shuffled) for the footprints in the layout excerpt that follows; sources: Cadence DE-HDL packaged netlist, KiCad conversion of 12092022_DA0F0TMDCD0_F0T_Management_Board_D_brd_V3_OCP.brd

C9  Q_CAP  100PF 50V 5% NPO  pkg 0402  page 20 : A = P1V2_AUX ; B = GND
R79  Q_RES  2K 1% CHIP  pkg 0402LF  page 11 : A = P3V3_AUX ; B = SGPIO_DO_0

(kicad_pcb
	(version 20260206)
	(generator "pcbnew")
	(generator_version "10.0")
	(general
		(thickness 1.6)
		(legacy_teardrops no)
	)
	(paper "A4")
	(title_block
		(title "12092022_DA0F0TMDCD0_F0T_Management_Board_D_brd_V3_OCP.brd")
		(comment 1 "Grand Teton / footprints 959-960 of 1440")
	)
	(layers
		(0 "F.Cu" signal "TOP")
		(4 "In1.Cu" signal "GND")
		(6 "In2.Cu" signal "IN1")
		(8 "In3.Cu" signal "GND1")
		(10 "In4.Cu" signal "IN2")
		(12 "In5.Cu" signal "VCC")
		(14 "In6.Cu" signal "VCC1")
		(16 "In7.Cu" signal "IN3")
		(18 "In8.Cu" signal "GND2")
		(20 "In9.Cu" signal "IN4")
		(22 "In10.Cu" signal "GND3")
		(2 "B.Cu" signal "BOTTOM")
		(9 "F.Adhes" user "F.Adhesive")
		(11 "B.Adhes" user "B.Adhesive")
		(13 "F.Paste" user "Package Geometry/Pastemask Top")
		(15 "B.Paste" user "Package Geometry/Pastemask Bottom")
		(5 "F.SilkS" user "Ref Des/Silkscreen Top")
		(7 "B.SilkS" user "Ref Des/Silkscreen Bottom")
		(1 "F.Mask" user "Board Geometry/Soldermask Top")
		(3 "B.Mask" user "Board Geometry/Soldermask Bottom")
		(17 "Dwgs.User" user "User.Drawings")
		(19 "Cmts.User" user "User.Comments")
		(21 "Eco1.User" user "User.Eco1")
		(23 "Eco2.User" user "User.Eco2")
		(25 "Edge.Cuts" user "Board Geometry/Outline")
		(27 "Margin" user)
		(31 "F.CrtYd" user "Package Geometry/Place Bound Top")
		(29 "B.CrtYd" user "Package Geometry/Place Bound Bottom")
		(35 "F.Fab" user "Ref Des/Assembly Top")
		(33 "B.Fab" user "Ref Des/Assembly Bottom")
	)
	(footprint ""
		(layer "B.Cu")
		(at 46.609 -107.3912)
		(property "Reference" "R79"
			(at 0 0 0)
			(layer "B.SilkS")
			(hide yes)
			(effects
				(font
					(size 1.27 1.27)
				)
				(justify mirror)
			)
		)
		(property "Value" ""
			(at 0 0 0)
			(layer "B.Fab")
			(effects
				(font
					(size 1.27 1.27)
				)
				(justify mirror)
			)
		)
		(duplicate_pad_numbers_are_jumpers no)
		(fp_line
			(start -0.7874 -0.4064)
			(end -0.7874 0.4064)
			(stroke
				(width 0.1524)
				(type default)
			)
			(layer "B.SilkS")
		)
		(fp_line
			(start -0.7874 0.4064)
			(end 0.7874 0.4064)
			(stroke
				(width 0.1524)
				(type default)
			)
			(layer "B.SilkS")
		)
		(fp_line
			(start 0.7874 -0.4064)
			(end -0.7874 -0.4064)
			(stroke
				(width 0.1524)
				(type default)
			)
			(layer "B.SilkS")
		)
		(fp_line
			(start 0.7874 0.4064)
			(end 0.7874 -0.4064)
			(stroke
				(width 0.1524)
				(type default)
			)
			(layer "B.SilkS")
		)
		(fp_line
			(start -0.67945 -0.3048)
			(end -0.67945 0.3048)
			(stroke
				(width 0.1)
				(type default)
			)
			(layer "B.Fab")
		)
		(fp_line
			(start -0.67945 0.3048)
			(end -0.120396 0.3048)
			(stroke
				(width 0.1)
				(type default)
			)
			(layer "B.Fab")
		)
		(fp_line
			(start -0.12065 -0.3048)
			(end -0.67945 -0.3048)
			(stroke
				(width 0.1)
				(type default)
			)
			(layer "B.Fab")
		)
		(fp_line
			(start -0.12065 -0.2794)
			(end -0.12065 -0.3048)
			(stroke
				(width 0.1)
				(type default)
			)
			(layer "B.Fab")
		)
		(fp_line
			(start -0.120396 0.2794)
			(end 0.12065 0.2794)
			(stroke
				(width 0.1)
				(type default)
			)
			(layer "B.Fab")
		)
		(fp_line
			(start -0.120396 0.3048)
			(end -0.120396 0.2794)
			(stroke
				(width 0.1)
				(type default)
			)
			(layer "B.Fab")
		)
		(fp_line
			(start 0.12065 -0.305054)
			(end 0.12065 -0.2794)
			(stroke
				(width 0.1)
				(type default)
			)
			(layer "B.Fab")
		)
		(fp_line
			(start 0.12065 -0.2794)
			(end -0.12065 -0.2794)
			(stroke
				(width 0.1)
				(type default)
			)
			(layer "B.Fab")
		)
		(fp_line
			(start 0.12065 0.2794)
			(end 0.12065 0.3048)
			(stroke
				(width 0.1)
				(type default)
			)
			(layer "B.Fab")
		)
		(fp_line
			(start 0.12065 0.3048)
			(end 0.67945 0.3048)
			(stroke
				(width 0.1)
				(type default)
			)
			(layer "B.Fab")
		)
		(fp_line
			(start 0.67945 -0.305054)
			(end 0.12065 -0.305054)
			(stroke
				(width 0.1)
				(type default)
			)
			(layer "B.Fab")
		)
		(fp_line
			(start 0.67945 0.3048)
			(end 0.67945 -0.305054)
			(stroke
				(width 0.1)
				(type default)
			)
			(layer "B.Fab")
		)
		(pad "1" smd circle
			(at 0.40005 0 180)
			(size 0 0)
			(layers "B.Cu" "B.Mask" "B.Paste")
			(net "P3V3_AUX")
		)
		(pad "2" smd circle
			(at -0.40005 0 180)
			(size 0 0)
			(layers "B.Cu" "B.Mask" "B.Paste")
			(net "SGPIO_DO_0")
		)
	)
	(footprint ""
		(layer "B.Cu")
		(at 80.546194 -53.342286 90)
		(property "Reference" "C9"
			(at 0 0 90)
			(layer "B.SilkS")
			(hide yes)
			(effects
				(font
					(size 1.27 1.27)
				)
				(justify mirror)
			)
		)
		(property "Value" ""
			(at 0 0 90)
			(layer "B.Fab")
			(effects
				(font
					(size 1.27 1.27)
				)
				(justify mirror)
			)
		)
		(duplicate_pad_numbers_are_jumpers no)
		(fp_line
			(start 0.7874 -0.4064)
			(end -0.7874 -0.4064)
			(stroke
				(width 0.1524)
				(type default)
			)
			(layer "B.SilkS")
		)
		(fp_line
			(start -0.7874 -0.4064)
			(end -0.7874 0.4064)
			(stroke
				(width 0.1524)
				(type default)
			)
			(layer "B.SilkS")
		)
		(fp_line
			(start 0.7874 0.4064)
			(end 0.7874 -0.4064)
			(stroke
				(width 0.1524)
				(type default)
			)
			(layer "B.SilkS")
		)
		(fp_line
			(start -0.7874 0.4064)
			(end 0.7874 0.4064)
			(stroke
				(width 0.1524)
				(type default)
			)
			(layer "B.SilkS")
		)
		(fp_line
			(start 0.67945 -0.305054)
			(end 0.12065 -0.305054)
			(stroke
				(width 0.1)
				(type default)
			)
			(layer "B.Fab")
		)
		(fp_line
			(start 0.12065 -0.305054)
			(end 0.12065 -0.2794)
			(stroke
				(width 0.1)
				(type default)
			)
			(layer "B.Fab")
		)
		(fp_line
			(start -0.12065 -0.3048)
			(end -0.67945 -0.3048)
			(stroke
				(width 0.1)
				(type default)
			)
			(layer "B.Fab")
		)
		(fp_line
			(start -0.67945 -0.3048)
			(end -0.67945 0.3048)
			(stroke
				(width 0.1)
				(type default)
			)
			(layer "B.Fab")
		)
		(fp_line
			(start 0.12065 -0.2794)
			(end -0.12065 -0.2794)
			(stroke
				(width 0.1)
				(type default)
			)
			(layer "B.Fab")
		)
		(fp_line
			(start -0.12065 -0.2794)
			(end -0.12065 -0.3048)
			(stroke
				(width 0.1)
				(type default)
			)
			(layer "B.Fab")
		)
		(fp_line
			(start 0.12065 0.2794)
			(end 0.12065 0.3048)
			(stroke
				(width 0.1)
				(type default)
			)
			(layer "B.Fab")
		)
		(fp_line
			(start -0.120396 0.2794)
			(end 0.12065 0.2794)
			(stroke
				(width 0.1)
				(type default)
			)
			(layer "B.Fab")
		)
		(fp_line
			(start 0.67945 0.3048)
			(end 0.67945 -0.305054)
			(stroke
				(width 0.1)
				(type default)
			)
			(layer "B.Fab")
		)
		(fp_line
			(start 0.12065 0.3048)
			(end 0.67945 0.3048)
			(stroke
				(width 0.1)
				(type default)
			)
			(layer "B.Fab")
		)
		(fp_line
			(start -0.120396 0.3048)
			(end -0.120396 0.2794)
			(stroke
				(width 0.1)
				(type default)
			)
			(layer "B.Fab")
		)
		(fp_line
			(start -0.67945 0.3048)
			(end -0.120396 0.3048)
			(stroke
				(width 0.1)
				(type default)
			)
			(layer "B.Fab")
		)
		(pad "1" smd circle
			(at 0.40005 0 270)
			(size 0 0)
			(layers "B.Cu" "B.Mask" "B.Paste")
			(net "P1V2_AUX")
		)
		(pad "2" smd circle
			(at -0.40005 0 270)
			(size 0 0)
			(layers "B.Cu" "B.Mask" "B.Paste")
			(net "GND")
		)
	)
)
